# S9S_MB_2U (Grand Teton) — schematic netlist excerpt (pin names and nets, part order shuffled) for the footprints in the layout excerpt that follows; sources: Cadence DE-HDL packaged netlist, KiCad conversion of 03242023_DA0F0TMBIJ0_F0T_Motherboard_J_brd_V01_OCP.brd

C1893  Q_CAP  0.01UF 50V 10% X7R  pkg C0402  page 217 : A = P3V3_AUX_FPGA_VCCIO4 ; B = GND
R29  Q_RES  35.7K 1% CHIP  pkg 0402LF  page 85 : A = PD_CHB_CPU0_DIMM2_SAA ; B = GND
C1915  Q_CAP  0.01UF 50V 10% X7R  pkg C0402  page 217 : A = P3V3_AUX_FPGA_VCCIO1 ; B = GND

(kicad_pcb
	(version 20260206)
	(generator "pcbnew")
	(generator_version "10.0")
	(general
		(thickness 1.6)
		(legacy_teardrops no)
	)
	(paper "A4")
	(title_block
		(title "03242023_DA0F0TMBIJ0_F0T_Motherboard_J_brd_V01_OCP.brd")
		(comment 1 "Grand Teton / footprints 5355-5357 of 6105")
	)
	(layers
		(0 "F.Cu" signal "TOP")
		(4 "In1.Cu" signal "GND")
		(6 "In2.Cu" signal "IN1")
		(8 "In3.Cu" signal "GND1")
		(10 "In4.Cu" signal "IN2")
		(12 "In5.Cu" signal "GND2")
		(14 "In6.Cu" signal "IN3")
		(16 "In7.Cu" signal "GND3")
		(18 "In8.Cu" signal "VCC")
		(20 "In9.Cu" signal "VCC1")
		(22 "In10.Cu" signal "GND4")
		(24 "In11.Cu" signal "IN4")
		(26 "In12.Cu" signal "GND5")
		(28 "In13.Cu" signal "IN5")
		(30 "In14.Cu" signal "GND6")
		(32 "In15.Cu" signal "IN6")
		(34 "In16.Cu" signal "GND7")
		(2 "B.Cu" signal "BOTTOM")
		(9 "F.Adhes" user "F.Adhesive")
		(11 "B.Adhes" user "B.Adhesive")
		(13 "F.Paste" user "Package Geometry/Pastemask Top")
		(15 "B.Paste" user "Package Geometry/Pastemask Bottom")
		(5 "F.SilkS" user "Ref Des/Silkscreen Top")
		(7 "B.SilkS" user "Ref Des/Silkscreen Bottom")
		(1 "F.Mask" user "Board Geometry/Soldermask Top")
		(3 "B.Mask" user "Board Geometry/Soldermask Bottom")
		(17 "Dwgs.User" user "User.Drawings")
		(19 "Cmts.User" user "User.Comments")
		(21 "Eco1.User" user "User.Eco1")
		(23 "Eco2.User" user "User.Eco2")
		(25 "Edge.Cuts" user "Board Geometry/Outline")
		(27 "Margin" user)
		(31 "F.CrtYd" user "Package Geometry/Place Bound Top")
		(29 "B.CrtYd" user "Package Geometry/Place Bound Bottom")
		(35 "F.Fab" user "Ref Des/Assembly Top")
		(33 "B.Fab" user "Ref Des/Assembly Bottom")
	)
	(footprint ""
		(layer "B.Cu")
		(at 179.755546 -115.775486 90)
		(property "Reference" "C1915"
			(at 0 0 90)
			(layer "B.SilkS")
			(hide yes)
			(effects
				(font
					(size 1.27 1.27)
				)
				(justify mirror)
			)
		)
		(property "Value" ""
			(at 0 0 90)
			(layer "B.Fab")
			(effects
				(font
					(size 1.27 1.27)
				)
				(justify mirror)
			)
		)
		(duplicate_pad_numbers_are_jumpers no)
		(fp_line
			(start 0.69215 -0.2921)
			(end -0.69215 -0.2921)
			(stroke
				(width 0.1524)
				(type default)
			)
			(layer "B.SilkS")
		)
		(fp_line
			(start -0.69215 -0.2921)
			(end -0.69215 0.2921)
			(stroke
				(width 0.1524)
				(type default)
			)
			(layer "B.SilkS")
		)
		(fp_line
			(start 0.69215 0.2921)
			(end 0.69215 -0.2921)
			(stroke
				(width 0.1524)
				(type default)
			)
			(layer "B.SilkS")
		)
		(fp_line
			(start -0.69215 0.2921)
			(end 0.69215 0.2921)
			(stroke
				(width 0.1524)
				(type default)
			)
			(layer "B.SilkS")
		)
		(fp_line
			(start 0.51435 -0.2794)
			(end -0.51435 -0.2794)
			(stroke
				(width 0.1)
				(type default)
			)
			(layer "B.Fab")
		)
		(fp_line
			(start -0.51435 -0.2794)
			(end -0.51435 0.2794)
			(stroke
				(width 0.1)
				(type default)
			)
			(layer "B.Fab")
		)
		(fp_line
			(start 0.51435 0.2794)
			(end 0.51435 -0.2794)
			(stroke
				(width 0.1)
				(type default)
			)
			(layer "B.Fab")
		)
		(fp_line
			(start -0.51435 0.2794)
			(end 0.51435 0.2794)
			(stroke
				(width 0.1)
				(type default)
			)
			(layer "B.Fab")
		)
		(pad "1" smd circle
			(at 0.40005 0 270)
			(size 0 0)
			(layers "B.Cu" "B.Mask" "B.Paste")
			(net "P3V3_AUX_FPGA_VCCIO1")
		)
		(pad "2" smd circle
			(at -0.40005 0 270)
			(size 0 0)
			(layers "B.Cu" "B.Mask" "B.Paste")
			(net "GND")
		)
		(zone
			(layer "B.Cu")
			(hatch none 0.5)
			(connect_pads
				(clearance 0)
			)
			(min_thickness 0.25)
			(keepout
				(tracks not_allowed)
				(vias allowed)
				(pads allowed)
				(copperpour not_allowed)
				(footprints allowed)
			)
			(placement
				(enabled no)
				(sheetname "")
			)
			(fill
				(thermal_gap 0.5)
				(thermal_bridge_width 0.5)
				(island_removal_mode 0)
			)
			(polygon
				(pts
					(xy 179.843176 -115.965986) (xy 179.901342 -115.874546) (xy 179.901342 -115.675156) (xy 179.843176 -115.584986)
					(xy 179.667916 -115.584986) (xy 179.609496 -115.675156) (xy 179.609496 -115.874546) (xy 179.667662 -115.965986)
				)
			)
		)
	)
	(footprint ""
		(layer "B.Cu")
		(at 295.628314 -319.177416 -90)
		(property "Reference" "R29"
			(at 0 0 90)
			(layer "B.SilkS")
			(hide yes)
			(effects
				(font
					(size 1.27 1.27)
				)
				(justify mirror)
			)
		)
		(property "Value" ""
			(at 0 0 90)
			(layer "B.Fab")
			(effects
				(font
					(size 1.27 1.27)
				)
				(justify mirror)
			)
		)
		(duplicate_pad_numbers_are_jumpers no)
		(fp_line
			(start -0.7874 0.4064)
			(end 0.7874 0.4064)
			(stroke
				(width 0.1524)
				(type default)
			)
			(layer "B.SilkS")
		)
		(fp_line
			(start 0.7874 0.4064)
			(end 0.7874 -0.4064)
			(stroke
				(width 0.1524)
				(type default)
			)
			(layer "B.SilkS")
		)
		(fp_line
			(start -0.7874 -0.4064)
			(end -0.7874 0.4064)
			(stroke
				(width 0.1524)
				(type default)
			)
			(layer "B.SilkS")
		)
		(fp_line
			(start 0.7874 -0.4064)
			(end -0.7874 -0.4064)
			(stroke
				(width 0.1524)
				(type default)
			)
			(layer "B.SilkS")
		)
		(fp_line
			(start -0.67945 0.3048)
			(end -0.120396 0.3048)
			(stroke
				(width 0.1)
				(type default)
			)
			(layer "B.Fab")
		)
		(fp_line
			(start -0.120396 0.3048)
			(end -0.120396 0.2794)
			(stroke
				(width 0.1)
				(type default)
			)
			(layer "B.Fab")
		)
		(fp_line
			(start 0.12065 0.3048)
			(end 0.67945 0.3048)
			(stroke
				(width 0.1)
				(type default)
			)
			(layer "B.Fab")
		)
		(fp_line
			(start 0.67945 0.3048)
			(end 0.67945 -0.305054)
			(stroke
				(width 0.1)
				(type default)
			)
			(layer "B.Fab")
		)
		(fp_line
			(start -0.120396 0.2794)
			(end 0.12065 0.2794)
			(stroke
				(width 0.1)
				(type default)
			)
			(layer "B.Fab")
		)
		(fp_line
			(start 0.12065 0.2794)
			(end 0.12065 0.3048)
			(stroke
				(width 0.1)
				(type default)
			)
			(layer "B.Fab")
		)
		(fp_line
			(start -0.12065 -0.2794)
			(end -0.12065 -0.3048)
			(stroke
				(width 0.1)
				(type default)
			)
			(layer "B.Fab")
		)
		(fp_line
			(start 0.12065 -0.2794)
			(end -0.12065 -0.2794)
			(stroke
				(width 0.1)
				(type default)
			)
			(layer "B.Fab")
		)
		(fp_line
			(start -0.67945 -0.3048)
			(end -0.67945 0.3048)
			(stroke
				(width 0.1)
				(type default)
			)
			(layer "B.Fab")
		)
		(fp_line
			(start -0.12065 -0.3048)
			(end -0.67945 -0.3048)
			(stroke
				(width 0.1)
				(type default)
			)
			(layer "B.Fab")
		)
		(fp_line
			(start 0.12065 -0.305054)
			(end 0.12065 -0.2794)
			(stroke
				(width 0.1)
				(type default)
			)
			(layer "B.Fab")
		)
		(fp_line
			(start 0.67945 -0.305054)
			(end 0.12065 -0.305054)
			(stroke
				(width 0.1)
				(type default)
			)
			(layer "B.Fab")
		)
		(pad "1" smd circle
			(at 0.40005 0 90)
			(size 0 0)
			(layers "B.Cu" "B.Mask" "B.Paste")
			(net "PD_CHB_CPU0_DIMM2_SAA")
		)
		(pad "2" smd circle
			(at -0.40005 0 90)
			(size 0 0)
			(layers "B.Cu" "B.Mask" "B.Paste")
			(net "GND")
		)
	)
	(footprint ""
		(layer "B.Cu")
		(at 178.9557 -110.975394 -90)
		(property "Reference" "C1893"
			(at 0 0 90)
			(layer "B.SilkS")
			(hide yes)
			(effects
				(font
					(size 1.27 1.27)
				)
				(justify mirror)
			)
		)
		(property "Value" ""
			(at 0 0 90)
			(layer "B.Fab")
			(effects
				(font
					(size 1.27 1.27)
				)
				(justify mirror)
			)
		)
		(duplicate_pad_numbers_are_jumpers no)
		(fp_line
			(start -0.69215 0.2921)
			(end 0.69215 0.2921)
			(stroke
				(width 0.1524)
				(type default)
			)
			(layer "B.SilkS")
		)
		(fp_line
			(start 0.69215 0.2921)
			(end 0.69215 -0.2921)
			(stroke
				(width 0.1524)
				(type default)
			)
			(layer "B.SilkS")
		)
		(fp_line
			(start -0.69215 -0.2921)
			(end -0.69215 0.2921)
			(stroke
				(width 0.1524)
				(type default)
			)
			(layer "B.SilkS")
		)
		(fp_line
			(start 0.69215 -0.2921)
			(end -0.69215 -0.2921)
			(stroke
				(width 0.1524)
				(type default)
			)
			(layer "B.SilkS")
		)
		(fp_line
			(start -0.51435 0.2794)
			(end 0.51435 0.2794)
			(stroke
				(width 0.1)
				(type default)
			)
			(layer "B.Fab")
		)
		(fp_line
			(start 0.51435 0.2794)
			(end 0.51435 -0.2794)
			(stroke
				(width 0.1)
				(type default)
			)
			(layer "B.Fab")
		)
		(fp_line
			(start -0.51435 -0.2794)
			(end -0.51435 0.2794)
			(stroke
				(width 0.1)
				(type default)
			)
			(layer "B.Fab")
		)
		(fp_line
			(start 0.51435 -0.2794)
			(end -0.51435 -0.2794)
			(stroke
				(width 0.1)
				(type default)
			)
			(layer "B.Fab")
		)
		(pad "1" smd circle
			(at 0.40005 0 90)
			(size 0 0)
			(layers "B.Cu" "B.Mask" "B.Paste")
			(net "P3V3_AUX_FPGA_VCCIO4")
		)
		(pad "2" smd circle
			(at -0.40005 0 90)
			(size 0 0)
			(layers "B.Cu" "B.Mask" "B.Paste")
			(net "GND")
		)
		(zone
			(layer "B.Cu")
			(hatch none 0.5)
			(connect_pads
				(clearance 0)
			)
			(min_thickness 0.25)
			(keepout
				(tracks not_allowed)
				(vias allowed)
				(pads allowed)
				(copperpour not_allowed)
				(footprints allowed)
			)
			(placement
				(enabled no)
				(sheetname "")
			)
			(fill
				(thermal_gap 0.5)
				(thermal_bridge_width 0.5)
				(island_removal_mode 0)
			)
			(polygon
				(pts
					(xy 178.86807 -110.784894) (xy 178.809904 -110.876334) (xy 178.809904 -111.075724) (xy 178.86807 -111.165894)
					(xy 179.04333 -111.165894) (xy 179.10175 -111.075724) (xy 179.10175 -110.876334) (xy 179.043584 -110.784894)
				)
			)
		)
	)
)
